# BASEBOARD_FAB2 (Tioga Pass) — schematic netlist excerpt (pin names and nets, part order shuffled) for the footprints in the layout excerpt that follows; sources: Cadence DE-HDL packaged netlist, KiCad conversion of Wiwynn_Tioga_Pass_MB.brd

C3M1  CAP  0.22UF 16V 10% X7R  pkg 0402  page 105 : A = P3E_CPU0_PE1_PCH_R_RXN<15> ; B = P3E_CPU0_PE1_PCH_RXN<15>
L2M1  INDUCTOR  0.022UH IND  pkg SMT  page 127 : INA = P1V05_PCH_STBY ; INB = P1V05_PCH_STBY_KR_PLL
R2R3  RES  10.0K 1% CHIP  pkg 0402  page 192 : A = P3V3_STBY ; B = FM_PLD_DEBUG_MODE_N

(kicad_pcb
	(version 20260206)
	(generator "pcbnew")
	(generator_version "10.0")
	(general
		(thickness 1.6)
		(legacy_teardrops no)
	)
	(paper "A4")
	(title_block
		(title "Wiwynn_Tioga_Pass_MB.brd")
		(comment 1 "Tioga Pass / footprints 3492-3494 of 4770")
	)
	(layers
		(0 "F.Cu" signal "TOP")
		(4 "In1.Cu" signal "L2GND")
		(6 "In2.Cu" signal "L3")
		(8 "In3.Cu" signal "L4GND")
		(10 "In4.Cu" signal "L5")
		(12 "In5.Cu" signal "L6GND")
		(14 "In6.Cu" signal "L7VCC")
		(16 "In7.Cu" signal "L8VCC")
		(18 "In8.Cu" signal "L9GND")
		(20 "In9.Cu" signal "L10")
		(22 "In10.Cu" signal "L11GND")
		(24 "In11.Cu" signal "L12")
		(26 "In12.Cu" signal "L13GND")
		(2 "B.Cu" signal "BOTTOM")
		(9 "F.Adhes" user "F.Adhesive")
		(11 "B.Adhes" user "B.Adhesive")
		(13 "F.Paste" user "Package Geometry/Pastemask Top")
		(15 "B.Paste" user "Package Geometry/Pastemask Bottom")
		(5 "F.SilkS" user "Ref Des/Silkscreen Top")
		(7 "B.SilkS" user "Ref Des/Silkscreen Bottom")
		(1 "F.Mask" user "Board Geometry/Soldermask Top")
		(3 "B.Mask" user "Board Geometry/Soldermask Bottom")
		(17 "Dwgs.User" user "User.Drawings")
		(19 "Cmts.User" user "User.Comments")
		(21 "Eco1.User" user "User.Eco1")
		(23 "Eco2.User" user "User.Eco2")
		(25 "Edge.Cuts" user "Board Geometry/Outline")
		(27 "Margin" user)
		(31 "F.CrtYd" user "Package Geometry/Place Bound Top")
		(29 "B.CrtYd" user "Package Geometry/Place Bound Bottom")
		(35 "F.Fab" user "Ref Des/Assembly Top")
		(33 "B.Fab" user "Ref Des/Assembly Bottom")
	)
	(footprint ""
		(layer "B.Cu")
		(at 405.369522 -113.7412)
		(property "Reference" "L2M1"
			(at 0 0 0)
			(layer "B.SilkS")
			(hide yes)
			(effects
				(font
					(size 1.27 1.27)
				)
				(justify mirror)
			)
		)
		(property "Value" ""
			(at 0 0 0)
			(layer "B.Fab")
			(effects
				(font
					(size 1.27 1.27)
				)
				(justify mirror)
			)
		)
		(duplicate_pad_numbers_are_jumpers no)
		(fp_rect
			(start 0.7239 1.93802)
			(end -0.7239 -0.26162)
			(stroke
				(width 0)
				(type default)
			)
			(fill no)
			(layer "B.CrtYd")
		)
		(fp_line
			(start -0.7239 -0.26162)
			(end 0.7239 -0.26162)
			(stroke
				(width 0.1)
				(type default)
			)
			(layer "B.Fab")
		)
		(fp_line
			(start -0.7239 1.93802)
			(end -0.7239 -0.26162)
			(stroke
				(width 0.1)
				(type default)
			)
			(layer "B.Fab")
		)
		(fp_line
			(start 0.7239 -0.26162)
			(end 0.7239 1.93802)
			(stroke
				(width 0.1)
				(type default)
			)
			(layer "B.Fab")
		)
		(fp_line
			(start 0.7239 1.93802)
			(end -0.7239 1.93802)
			(stroke
				(width 0.1)
				(type default)
			)
			(layer "B.Fab")
		)
		(pad "1" smd rect
			(at 0 0 180)
			(size 1.4986 0.9144)
			(layers "B.Cu" "B.Mask" "B.Paste")
			(net "P1V05_PCH_STBY")
		)
		(pad "2" smd rect
			(at 0 1.6764 180)
			(size 1.4986 0.9144)
			(layers "B.Cu" "B.Mask" "B.Paste")
			(net "P1V05_PCH_STBY_KR_PLL")
		)
		(zone
			(layer "B.Cu")
			(hatch none 0.5)
			(connect_pads
				(clearance 0)
			)
			(min_thickness 0.25)
			(keepout
				(tracks allowed)
				(vias not_allowed)
				(pads allowed)
				(copperpour not_allowed)
				(footprints allowed)
			)
			(placement
				(enabled no)
				(sheetname "")
			)
			(fill
				(thermal_gap 0.5)
				(thermal_bridge_width 0.5)
				(island_removal_mode 0)
			)
			(polygon
				(pts
					(xy 406.118822 -113.284) (xy 406.118822 -112.522) (xy 404.620222 -112.522) (xy 404.620222 -113.284)
				)
			)
		)
		(zone
			(layer "B.Cu")
			(hatch none 0.5)
			(connect_pads
				(clearance 0)
			)
			(min_thickness 0.25)
			(keepout
				(tracks not_allowed)
				(vias allowed)
				(pads allowed)
				(copperpour not_allowed)
				(footprints allowed)
			)
			(placement
				(enabled no)
				(sheetname "")
			)
			(fill
				(thermal_gap 0.5)
				(thermal_bridge_width 0.5)
				(island_removal_mode 0)
			)
			(polygon
				(pts
					(xy 406.118822 -112.522) (xy 406.118822 -113.284) (xy 404.620222 -113.284) (xy 404.620222 -112.522)
				)
			)
		)
	)
	(footprint ""
		(layer "B.Cu")
		(at 355.178614 -125.532642 -90)
		(property "Reference" "C3M1"
			(at 0 0 90)
			(layer "B.SilkS")
			(hide yes)
			(effects
				(font
					(size 1.27 1.27)
				)
				(justify mirror)
			)
		)
		(property "Value" ""
			(at 0 0 90)
			(layer "B.Fab")
			(effects
				(font
					(size 1.27 1.27)
				)
				(justify mirror)
			)
		)
		(duplicate_pad_numbers_are_jumpers no)
		(fp_poly
			(pts
				(xy -0.3048 -0.1016) (xy -0.3048 0.9906) (xy 0.3048 0.9906) (xy 0.3048 -0.1016)
			)
			(stroke
				(width 0)
				(type default)
			)
			(fill no)
			(layer "B.CrtYd")
		)
		(fp_line
			(start -0.3048 0.9906)
			(end -0.3048 -0.1016)
			(stroke
				(width 0.1)
				(type default)
			)
			(layer "B.Fab")
		)
		(fp_line
			(start 0.3048 0.9906)
			(end -0.3048 0.9906)
			(stroke
				(width 0.1)
				(type default)
			)
			(layer "B.Fab")
		)
		(fp_line
			(start -0.3048 -0.1016)
			(end 0.3048 -0.1016)
			(stroke
				(width 0.1)
				(type default)
			)
			(layer "B.Fab")
		)
		(fp_line
			(start 0.3048 -0.1016)
			(end 0.3048 0.9906)
			(stroke
				(width 0.1)
				(type default)
			)
			(layer "B.Fab")
		)
		(pad "1" smd rect
			(at 0 0 90)
			(size 0.508 0.508)
			(layers "B.Cu" "B.Mask" "B.Paste")
			(net "P3E_CPU0_PE1_PCH_R_RXN<15>")
		)
		(pad "2" smd rect
			(at 0 0.889 90)
			(size 0.508 0.508)
			(layers "B.Cu" "B.Mask" "B.Paste")
			(net "P3E_CPU0_PE1_PCH_RXN<15>")
		)
		(zone
			(layer "B.Cu")
			(hatch none 0.5)
			(connect_pads
				(clearance 0)
			)
			(min_thickness 0.25)
			(keepout
				(tracks not_allowed)
				(vias allowed)
				(pads allowed)
				(copperpour not_allowed)
				(footprints allowed)
			)
			(placement
				(enabled no)
				(sheetname "")
			)
			(fill
				(thermal_gap 0.5)
				(thermal_bridge_width 0.5)
				(island_removal_mode 0)
			)
			(polygon
				(pts
					(xy 354.543614 -125.278642) (xy 354.543614 -125.786642) (xy 354.924614 -125.786642) (xy 354.924614 -125.278642)
				)
			)
		)
		(zone
			(layer "B.Cu")
			(hatch none 0.5)
			(connect_pads
				(clearance 0)
			)
			(min_thickness 0.25)
			(keepout
				(tracks allowed)
				(vias not_allowed)
				(pads allowed)
				(copperpour not_allowed)
				(footprints allowed)
			)
			(placement
				(enabled no)
				(sheetname "")
			)
			(fill
				(thermal_gap 0.5)
				(thermal_bridge_width 0.5)
				(island_removal_mode 0)
			)
			(polygon
				(pts
					(xy 354.924614 -125.278642) (xy 354.924614 -125.786642) (xy 354.543614 -125.786642) (xy 354.543614 -125.278642)
				)
			)
		)
	)
	(footprint ""
		(layer "B.Cu")
		(at 374.65 -66.04 180)
		(property "Reference" "R2R3"
			(at 0 0 0)
			(layer "B.SilkS")
			(hide yes)
			(effects
				(font
					(size 1.27 1.27)
				)
				(justify mirror)
			)
		)
		(property "Value" ""
			(at 0 0 0)
			(layer "B.Fab")
			(effects
				(font
					(size 1.27 1.27)
				)
				(justify mirror)
			)
		)
		(duplicate_pad_numbers_are_jumpers no)
		(fp_poly
			(pts
				(xy 0.2794 -0.1016) (xy -0.2794 -0.1016) (xy -0.2794 0.9906) (xy 0.2794 0.9906)
			)
			(stroke
				(width 0)
				(type default)
			)
			(fill no)
			(layer "B.CrtYd")
		)
		(fp_line
			(start 0.2794 0.9906)
			(end -0.2794 0.9906)
			(stroke
				(width 0.1)
				(type default)
			)
			(layer "B.Fab")
		)
		(fp_line
			(start 0.2794 -0.1016)
			(end 0.2794 0.9906)
			(stroke
				(width 0.1)
				(type default)
			)
			(layer "B.Fab")
		)
		(fp_line
			(start -0.2794 0.9906)
			(end -0.2794 -0.1016)
			(stroke
				(width 0.1)
				(type default)
			)
			(layer "B.Fab")
		)
		(fp_line
			(start -0.2794 -0.1016)
			(end 0.2794 -0.1016)
			(stroke
				(width 0.1)
				(type default)
			)
			(layer "B.Fab")
		)
		(pad "1" smd rect
			(at 0 0)
			(size 0.508 0.508)
			(layers "B.Cu" "B.Mask" "B.Paste")
			(net "P3V3_STBY")
		)
		(pad "2" smd rect
			(at 0 0.889)
			(size 0.508 0.508)
			(layers "B.Cu" "B.Mask" "B.Paste")
			(net "FM_PLD_DEBUG_MODE_N")
		)
		(zone
			(layer "B.Cu")
			(hatch none 0.5)
			(connect_pads
				(clearance 0)
			)
			(min_thickness 0.25)
			(keepout
				(tracks not_allowed)
				(vias allowed)
				(pads allowed)
				(copperpour not_allowed)
				(footprints allowed)
			)
			(placement
				(enabled no)
				(sheetname "")
			)
			(fill
				(thermal_gap 0.5)
				(thermal_bridge_width 0.5)
				(island_removal_mode 0)
			)
			(polygon
				(pts
					(xy 374.396 -66.675) (xy 374.904 -66.675) (xy 374.904 -66.294) (xy 374.396 -66.294)
				)
			)
		)
		(zone
			(layer "B.Cu")
			(hatch none 0.5)
			(connect_pads
				(clearance 0)
			)
			(min_thickness 0.25)
			(keepout
				(tracks allowed)
				(vias not_allowed)
				(pads allowed)
				(copperpour not_allowed)
				(footprints allowed)
			)
			(placement
				(enabled no)
				(sheetname "")
			)
			(fill
				(thermal_gap 0.5)
				(thermal_bridge_width 0.5)
				(island_removal_mode 0)
			)
			(polygon
				(pts
					(xy 374.396 -66.294) (xy 374.904 -66.294) (xy 374.904 -66.675) (xy 374.396 -66.675)
				)
			)
		)
	)
)
